# T6G (Grand Teton) — schematic netlist excerpt (pin names and nets, part order shuffled) for the footprints in the layout excerpt that follows; sources: Cadence DE-HDL packaged netlist, KiCad conversion of 04192023_DAF0TMB3IC0_F0TG_MB_C_brd_V02_OCP.brd

PL61  Q_INDUCTOR4P_14  150NH IND  pkg L_TLM117513Q-151QL_11X7-5XA  page 196
  \1\  = SW_PVDDCR_CPU0_P0_SW5
  \2\  = IND_CPU0_P0_CPL6
  \3\  = IND_CPU0_P0_CPL5
  \4\  = PVDDCR_CPU0_P0

PR830  Q_RES  15K 0.1% CHIP  pkg 0402LF  page 190 : A = P3V3_AUX_FB ; B = GND
R1028  Q_RES  10K 1% CHIP  pkg 0201LF  page 287 : A = GPIO2_RT_CPU0_P1 ; B = GND

(kicad_pcb
	(version 20260206)
	(generator "pcbnew")
	(generator_version "10.0")
	(general
		(thickness 1.6)
		(legacy_teardrops no)
	)
	(paper "A4")
	(title_block
		(title "04192023_DAF0TMB3IC0_F0TG_MB_C_brd_V02_OCP.brd")
		(comment 1 "Grand Teton / footprints 4564-4566 of 8354")
	)
	(layers
		(0 "F.Cu" signal "TOP")
		(4 "In1.Cu" signal "GND")
		(6 "In2.Cu" signal "IN1")
		(8 "In3.Cu" signal "GND1")
		(10 "In4.Cu" signal "IN2")
		(12 "In5.Cu" signal "GND2")
		(14 "In6.Cu" signal "IN3")
		(16 "In7.Cu" signal "GND3")
		(18 "In8.Cu" signal "VCC")
		(20 "In9.Cu" signal "VCC1")
		(22 "In10.Cu" signal "GND4")
		(24 "In11.Cu" signal "IN4")
		(26 "In12.Cu" signal "GND5")
		(28 "In13.Cu" signal "IN5")
		(30 "In14.Cu" signal "GND6")
		(32 "In15.Cu" signal "IN6")
		(34 "In16.Cu" signal "GND7")
		(2 "B.Cu" signal "BOTTOM")
		(9 "F.Adhes" user "F.Adhesive")
		(11 "B.Adhes" user "B.Adhesive")
		(13 "F.Paste" user "Package Geometry/Pastemask Top")
		(15 "B.Paste" user "Package Geometry/Pastemask Bottom")
		(5 "F.SilkS" user "Ref Des/Silkscreen Top")
		(7 "B.SilkS" user "Ref Des/Silkscreen Bottom")
		(1 "F.Mask" user "Board Geometry/Soldermask Top")
		(3 "B.Mask" user "Board Geometry/Soldermask Bottom")
		(17 "Dwgs.User" user "User.Drawings")
		(19 "Cmts.User" user "User.Comments")
		(21 "Eco1.User" user "User.Eco1")
		(23 "Eco2.User" user "User.Eco2")
		(25 "Edge.Cuts" user "Board Geometry/Outline")
		(27 "Margin" user)
		(31 "F.CrtYd" user "Package Geometry/Place Bound Top")
		(29 "B.CrtYd" user "Package Geometry/Place Bound Bottom")
		(35 "F.Fab" user "Ref Des/Assembly Top")
		(33 "B.Fab" user "Ref Des/Assembly Bottom")
	)
	(footprint ""
		(layer "F.Cu")
		(at 355.915722 -178.813206 180)
		(property "Reference" "PL61"
			(at 3.57124 8.140954 0)
			(unlocked yes)
			(layer "F.SilkS")
			(effects
				(font
					(size 0.7874 0.5842)
					(thickness 0.1524)
				)
				(justify left)
			)
		)
		(property "Value" ""
			(at 0 0 180)
			(layer "F.Fab")
			(effects
				(font
					(size 1.27 1.27)
				)
			)
		)
		(duplicate_pad_numbers_are_jumpers no)
		(fp_line
			(start 3.750056 5.500116)
			(end 3.750056 -5.500116)
			(stroke
				(width 0.1524)
				(type default)
			)
			(layer "F.SilkS")
		)
		(fp_line
			(start 3.750056 -5.500116)
			(end 2.393442 -5.500116)
			(stroke
				(width 0.1524)
				(type default)
			)
			(layer "F.SilkS")
		)
		(fp_line
			(start 2.393442 5.500116)
			(end 3.750056 5.500116)
			(stroke
				(width 0.1524)
				(type default)
			)
			(layer "F.SilkS")
		)
		(fp_line
			(start -2.393442 5.500116)
			(end -3.750056 5.500116)
			(stroke
				(width 0.1524)
				(type default)
			)
			(layer "F.SilkS")
		)
		(fp_line
			(start -3.750056 5.500116)
			(end -3.750056 -5.500116)
			(stroke
				(width 0.1524)
				(type default)
			)
			(layer "F.SilkS")
		)
		(fp_line
			(start -3.750056 -5.500116)
			(end -2.393442 -5.500116)
			(stroke
				(width 0.1524)
				(type default)
			)
			(layer "F.SilkS")
		)
		(fp_poly
			(pts
				(xy -4.149598 -5.301742) (xy -5.165598 -4.793742) (xy -5.165598 -5.809742)
			)
			(stroke
				(width 0)
				(type default)
			)
			(fill yes)
			(layer "F.SilkS")
		)
		(fp_line
			(start 3.750056 5.500116)
			(end 3.750056 -5.500116)
			(stroke
				(width 0.1)
				(type default)
			)
			(layer "F.Fab")
		)
		(fp_line
			(start 3.750056 -5.500116)
			(end -3.750056 -5.500116)
			(stroke
				(width 0.1)
				(type default)
			)
			(layer "F.Fab")
		)
		(fp_line
			(start -3.750056 5.500116)
			(end 3.750056 5.500116)
			(stroke
				(width 0.1)
				(type default)
			)
			(layer "F.Fab")
		)
		(fp_line
			(start -3.750056 -5.500116)
			(end -3.750056 5.500116)
			(stroke
				(width 0.1)
				(type default)
			)
			(layer "F.Fab")
		)
		(fp_poly
			(pts
				(xy -4.9276 -4.757928) (xy -4.9276 -3.741928) (xy -3.9116 -4.249928)
			)
			(stroke
				(width 0)
				(type default)
			)
			(fill yes)
			(layer "F.Fab")
		)
		(pad "1" smd rect
			(at 0 -4.249928 90)
			(size 2.413 4.5212)
			(layers "F.Cu" "F.Mask" "F.Paste")
			(net "SW_PVDDCR_CPU0_P0_SW5")
		)
		(pad "2" smd rect
			(at 0 -1.175004 90)
			(size 1.3716 4.5212)
			(layers "F.Cu" "F.Mask" "F.Paste")
			(net "IND_CPU0_P0_CPL6")
		)
		(pad "3" smd rect
			(at 0 1.175004 90)
			(size 1.3716 4.5212)
			(layers "F.Cu" "F.Mask" "F.Paste")
			(net "IND_CPU0_P0_CPL5")
		)
		(pad "4" smd rect
			(at 0 4.249928 90)
			(size 2.413 4.5212)
			(layers "F.Cu" "F.Mask" "F.Paste")
			(net "PVDDCR_CPU0_P0")
		)
	)
	(footprint ""
		(layer "F.Cu")
		(at 457.329794 -46.264576 -90)
		(property "Reference" "PR830"
			(at 0 0 270)
			(layer "F.SilkS")
			(hide yes)
			(effects
				(font
					(size 1.27 1.27)
				)
			)
		)
		(property "Value" ""
			(at 0 0 270)
			(layer "F.Fab")
			(effects
				(font
					(size 1.27 1.27)
				)
			)
		)
		(duplicate_pad_numbers_are_jumpers no)
		(fp_line
			(start -0.7874 0.4064)
			(end -0.7874 -0.4064)
			(stroke
				(width 0.1524)
				(type default)
			)
			(layer "F.SilkS")
		)
		(fp_line
			(start 0.7874 0.4064)
			(end -0.7874 0.4064)
			(stroke
				(width 0.1524)
				(type default)
			)
			(layer "F.SilkS")
		)
		(fp_line
			(start -0.7874 -0.4064)
			(end 0.7874 -0.4064)
			(stroke
				(width 0.1524)
				(type default)
			)
			(layer "F.SilkS")
		)
		(fp_line
			(start 0.7874 -0.4064)
			(end 0.7874 0.4064)
			(stroke
				(width 0.1524)
				(type default)
			)
			(layer "F.SilkS")
		)
		(fp_line
			(start -0.67945 0.3048)
			(end -0.67945 -0.305054)
			(stroke
				(width 0.1)
				(type default)
			)
			(layer "F.Fab")
		)
		(fp_line
			(start -0.12065 0.3048)
			(end -0.67945 0.3048)
			(stroke
				(width 0.1)
				(type default)
			)
			(layer "F.Fab")
		)
		(fp_line
			(start 0.120396 0.3048)
			(end 0.120396 0.2794)
			(stroke
				(width 0.1)
				(type default)
			)
			(layer "F.Fab")
		)
		(fp_line
			(start 0.67945 0.3048)
			(end 0.120396 0.3048)
			(stroke
				(width 0.1)
				(type default)
			)
			(layer "F.Fab")
		)
		(fp_line
			(start -0.12065 0.2794)
			(end -0.12065 0.3048)
			(stroke
				(width 0.1)
				(type default)
			)
			(layer "F.Fab")
		)
		(fp_line
			(start 0.120396 0.2794)
			(end -0.12065 0.2794)
			(stroke
				(width 0.1)
				(type default)
			)
			(layer "F.Fab")
		)
		(fp_line
			(start -0.12065 -0.2794)
			(end 0.12065 -0.2794)
			(stroke
				(width 0.1)
				(type default)
			)
			(layer "F.Fab")
		)
		(fp_line
			(start 0.12065 -0.2794)
			(end 0.12065 -0.3048)
			(stroke
				(width 0.1)
				(type default)
			)
			(layer "F.Fab")
		)
		(fp_line
			(start 0.12065 -0.3048)
			(end 0.67945 -0.3048)
			(stroke
				(width 0.1)
				(type default)
			)
			(layer "F.Fab")
		)
		(fp_line
			(start 0.67945 -0.3048)
			(end 0.67945 0.3048)
			(stroke
				(width 0.1)
				(type default)
			)
			(layer "F.Fab")
		)
		(fp_line
			(start -0.67945 -0.305054)
			(end -0.12065 -0.305054)
			(stroke
				(width 0.1)
				(type default)
			)
			(layer "F.Fab")
		)
		(fp_line
			(start -0.12065 -0.305054)
			(end -0.12065 -0.2794)
			(stroke
				(width 0.1)
				(type default)
			)
			(layer "F.Fab")
		)
		(pad "1" smd circle
			(at -0.40005 0 270)
			(size 0 0)
			(layers "F.Cu" "F.Mask" "F.Paste")
			(net "P3V3_AUX_FB")
		)
		(pad "2" smd circle
			(at 0.40005 0 270)
			(size 0 0)
			(layers "F.Cu" "F.Mask" "F.Paste")
			(net "GND")
		)
	)
	(footprint ""
		(layer "F.Cu")
		(at 331.793342 -393.96416)
		(property "Reference" "R1028"
			(at 0 0 0)
			(layer "F.SilkS")
			(hide yes)
			(effects
				(font
					(size 1.27 1.27)
				)
			)
		)
		(property "Value" ""
			(at 0 0 0)
			(layer "F.Fab")
			(effects
				(font
					(size 1.27 1.27)
				)
			)
		)
		(duplicate_pad_numbers_are_jumpers no)
		(fp_line
			(start -0.32512 -0.175006)
			(end 0.32512 -0.175006)
			(stroke
				(width 0.1)
				(type default)
			)
			(layer "F.Fab")
		)
		(fp_line
			(start -0.32512 0.175006)
			(end -0.32512 -0.175006)
			(stroke
				(width 0.1)
				(type default)
			)
			(layer "F.Fab")
		)
		(fp_line
			(start 0.32512 -0.175006)
			(end 0.32512 0.175006)
			(stroke
				(width 0.1)
				(type default)
			)
			(layer "F.Fab")
		)
		(fp_line
			(start 0.32512 0.175006)
			(end -0.32512 0.175006)
			(stroke
				(width 0.1)
				(type default)
			)
			(layer "F.Fab")
		)
		(pad "1" smd rect
			(at -0.2667 0)
			(size 0.3048 0.381)
			(layers "F.Cu" "F.Mask" "F.Paste")
			(net "GPIO2_RT_CPU0_P1")
		)
		(pad "2" smd rect
			(at 0.2667 0 180)
			(size 0.3048 0.381)
			(layers "F.Cu" "F.Mask" "F.Paste")
			(net "GND")
		)
	)
)
